(kicad_pcb
	(version 20260206)
	(generator "pcbnew")
	(generator_version "10.0")
	(general
		(thickness 1.6)
		(legacy_teardrops no)
	)
	(paper "A4")
	(title_block
		(title "01162023_DA0F0TEBIF0_F0T_Expander_BD_F_brd_V02_OCP.brd")
		(comment 1 "Grand Teton / footprints 9015-9023 of 9728")
	)
	(layers
		(0 "F.Cu" signal "TOP")
		(4 "In1.Cu" signal "GND")
		(6 "In2.Cu" signal "VCC")
		(8 "In3.Cu" signal "VCC1")
		(10 "In4.Cu" signal "GND1")
		(12 "In5.Cu" signal "IN1")
		(14 "In6.Cu" signal "GND2")
		(16 "In7.Cu" signal "IN2")
		(18 "In8.Cu" signal "GND3")
		(20 "In9.Cu" signal "IN3")
		(22 "In10.Cu" signal "GND4")
		(24 "In11.Cu" signal "IN4")
		(26 "In12.Cu" signal "GND5")
		(28 "In13.Cu" signal "IN5")
		(30 "In14.Cu" signal "GND6")
		(32 "In15.Cu" signal "IN6")
		(34 "In16.Cu" signal "GND7")
		(2 "B.Cu" signal "BOTTOM")
		(9 "F.Adhes" user "F.Adhesive")
		(11 "B.Adhes" user "B.Adhesive")
		(13 "F.Paste" user "Package Geometry/Pastemask Top")
		(15 "B.Paste" user "Package Geometry/Pastemask Bottom")
		(5 "F.SilkS" user "Ref Des/Silkscreen Top")
		(7 "B.SilkS" user "Ref Des/Silkscreen Bottom")
		(1 "F.Mask" user "Board Geometry/Soldermask Top")
		(3 "B.Mask" user "Board Geometry/Soldermask Bottom")
		(17 "Dwgs.User" user "User.Drawings")
		(19 "Cmts.User" user "User.Comments")
		(21 "Eco1.User" user "User.Eco1")
		(23 "Eco2.User" user "User.Eco2")
		(25 "Edge.Cuts" user "Board Geometry/Outline")
		(27 "Margin" user)
		(31 "F.CrtYd" user "Package Geometry/Place Bound Top")
		(29 "B.CrtYd" user "Package Geometry/Place Bound Bottom")
		(35 "F.Fab" user "Ref Des/Assembly Top")
		(33 "B.Fab" user "Ref Des/Assembly Bottom")
	)
	(footprint ""
		(layer "B.Cu")
		(at 175.749966 -303.499774 -90)
		(property "Reference" "C3084"
			(at 0 0 90)
			(layer "B.SilkS")
			(hide yes)
			(effects
				(font
					(size 1.27 1.27)
				)
				(justify mirror)
			)
		)
		(property "Value" ""
			(at 0 0 90)
			(layer "B.Fab")
			(effects
				(font
					(size 1.27 1.27)
				)
				(justify mirror)
			)
		)
		(duplicate_pad_numbers_are_jumpers no)
		(fp_line
			(start -0.299974 0.150114)
			(end 0.299974 0.150114)
			(stroke
				(width 0.1)
				(type default)
			)
			(layer "B.Fab")
		)
		(fp_line
			(start 0.299974 0.150114)
			(end 0.299974 -0.150114)
			(stroke
				(width 0.1)
				(type default)
			)
			(layer "B.Fab")
		)
		(fp_line
			(start -0.299974 -0.150114)
			(end -0.299974 0.150114)
			(stroke
				(width 0.1)
				(type default)
			)
			(layer "B.Fab")
		)
		(fp_line
			(start 0.299974 -0.150114)
			(end -0.299974 -0.150114)
			(stroke
				(width 0.1)
				(type default)
			)
			(layer "B.Fab")
		)
		(pad "1" smd rect
			(at 0.2667 0 90)
			(size 0.3048 0.381)
			(layers "B.Cu" "B.Mask" "B.Paste")
			(net "P1V25_PEX1")
		)
		(pad "2" smd rect
			(at -0.2667 0 90)
			(size 0.3048 0.381)
			(layers "B.Cu" "B.Mask" "B.Paste")
			(net "GND")
		)
	)
	(footprint ""
		(layer "B.Cu")
		(at 133.030214 -213.524846 180)
		(property "Reference" "R997"
			(at 0 0 0)
			(layer "B.SilkS")
			(hide yes)
			(effects
				(font
					(size 1.27 1.27)
				)
				(justify mirror)
			)
		)
		(property "Value" ""
			(at 0 0 0)
			(layer "B.Fab")
			(effects
				(font
					(size 1.27 1.27)
				)
				(justify mirror)
			)
		)
		(duplicate_pad_numbers_are_jumpers no)
		(fp_line
			(start 0.7874 0.4064)
			(end 0.7874 -0.4064)
			(stroke
				(width 0.1524)
				(type default)
			)
			(layer "B.SilkS")
		)
		(fp_line
			(start 0.7874 -0.4064)
			(end -0.7874 -0.4064)
			(stroke
				(width 0.1524)
				(type default)
			)
			(layer "B.SilkS")
		)
		(fp_line
			(start -0.7874 0.4064)
			(end 0.7874 0.4064)
			(stroke
				(width 0.1524)
				(type default)
			)
			(layer "B.SilkS")
		)
		(fp_line
			(start -0.7874 -0.4064)
			(end -0.7874 0.4064)
			(stroke
				(width 0.1524)
				(type default)
			)
			(layer "B.SilkS")
		)
		(fp_line
			(start 0.67945 0.3048)
			(end 0.67945 -0.305054)
			(stroke
				(width 0.1)
				(type default)
			)
			(layer "B.Fab")
		)
		(fp_line
			(start 0.67945 -0.305054)
			(end 0.12065 -0.305054)
			(stroke
				(width 0.1)
				(type default)
			)
			(layer "B.Fab")
		)
		(fp_line
			(start 0.12065 0.3048)
			(end 0.67945 0.3048)
			(stroke
				(width 0.1)
				(type default)
			)
			(layer "B.Fab")
		)
		(fp_line
			(start 0.12065 0.2794)
			(end 0.12065 0.3048)
			(stroke
				(width 0.1)
				(type default)
			)
			(layer "B.Fab")
		)
		(fp_line
			(start 0.12065 -0.2794)
			(end -0.12065 -0.2794)
			(stroke
				(width 0.1)
				(type default)
			)
			(layer "B.Fab")
		)
		(fp_line
			(start 0.12065 -0.305054)
			(end 0.12065 -0.2794)
			(stroke
				(width 0.1)
				(type default)
			)
			(layer "B.Fab")
		)
		(fp_line
			(start -0.120396 0.3048)
			(end -0.120396 0.2794)
			(stroke
				(width 0.1)
				(type default)
			)
			(layer "B.Fab")
		)
		(fp_line
			(start -0.120396 0.2794)
			(end 0.12065 0.2794)
			(stroke
				(width 0.1)
				(type default)
			)
			(layer "B.Fab")
		)
		(fp_line
			(start -0.12065 -0.2794)
			(end -0.12065 -0.3048)
			(stroke
				(width 0.1)
				(type default)
			)
			(layer "B.Fab")
		)
		(fp_line
			(start -0.12065 -0.3048)
			(end -0.67945 -0.3048)
			(stroke
				(width 0.1)
				(type default)
			)
			(layer "B.Fab")
		)
		(fp_line
			(start -0.67945 0.3048)
			(end -0.120396 0.3048)
			(stroke
				(width 0.1)
				(type default)
			)
			(layer "B.Fab")
		)
		(fp_line
			(start -0.67945 -0.3048)
			(end -0.67945 0.3048)
			(stroke
				(width 0.1)
				(type default)
			)
			(layer "B.Fab")
		)
		(pad "1" smd circle
			(at 0.40005 0)
			(size 0 0)
			(layers "B.Cu" "B.Mask" "B.Paste")
			(net "UART_PEX2_CLI_BUF_R_TX")
		)
		(pad "2" smd circle
			(at -0.40005 0)
			(size 0 0)
			(layers "B.Cu" "B.Mask" "B.Paste")
			(net "UART_PEX2_CLI_BUF_TX")
		)
	)
	(footprint ""
		(layer "B.Cu")
		(at 411.750002 -288.299906 90)
		(property "Reference" "C3442"
			(at 0 0 90)
			(layer "B.SilkS")
			(hide yes)
			(effects
				(font
					(size 1.27 1.27)
				)
				(justify mirror)
			)
		)
		(property "Value" ""
			(at 0 0 90)
			(layer "B.Fab")
			(effects
				(font
					(size 1.27 1.27)
				)
				(justify mirror)
			)
		)
		(duplicate_pad_numbers_are_jumpers no)
		(fp_line
			(start 0.299974 -0.150114)
			(end -0.299974 -0.150114)
			(stroke
				(width 0.1)
				(type default)
			)
			(layer "B.Fab")
		)
		(fp_line
			(start -0.299974 -0.150114)
			(end -0.299974 0.150114)
			(stroke
				(width 0.1)
				(type default)
			)
			(layer "B.Fab")
		)
		(fp_line
			(start 0.299974 0.150114)
			(end 0.299974 -0.150114)
			(stroke
				(width 0.1)
				(type default)
			)
			(layer "B.Fab")
		)
		(fp_line
			(start -0.299974 0.150114)
			(end 0.299974 0.150114)
			(stroke
				(width 0.1)
				(type default)
			)
			(layer "B.Fab")
		)
		(pad "1" smd rect
			(at 0.2667 0 270)
			(size 0.3048 0.381)
			(layers "B.Cu" "B.Mask" "B.Paste")
			(net "P1V25_PEX3")
		)
		(pad "2" smd rect
			(at -0.2667 0 270)
			(size 0.3048 0.381)
			(layers "B.Cu" "B.Mask" "B.Paste")
			(net "GND")
		)
	)
	(footprint ""
		(layer "B.Cu")
		(at 130.893058 -227.965 180)
		(property "Reference" "R3469"
			(at 0 0 0)
			(layer "B.SilkS")
			(hide yes)
			(effects
				(font
					(size 1.27 1.27)
				)
				(justify mirror)
			)
		)
		(property "Value" ""
			(at 0 0 0)
			(layer "B.Fab")
			(effects
				(font
					(size 1.27 1.27)
				)
				(justify mirror)
			)
		)
		(duplicate_pad_numbers_are_jumpers no)
		(fp_line
			(start 0.7874 0.4064)
			(end 0.7874 -0.4064)
			(stroke
				(width 0.1524)
				(type default)
			)
			(layer "B.SilkS")
		)
		(fp_line
			(start 0.7874 -0.4064)
			(end -0.7874 -0.4064)
			(stroke
				(width 0.1524)
				(type default)
			)
			(layer "B.SilkS")
		)
		(fp_line
			(start -0.7874 0.4064)
			(end 0.7874 0.4064)
			(stroke
				(width 0.1524)
				(type default)
			)
			(layer "B.SilkS")
		)
		(fp_line
			(start -0.7874 -0.4064)
			(end -0.7874 0.4064)
			(stroke
				(width 0.1524)
				(type default)
			)
			(layer "B.SilkS")
		)
		(fp_line
			(start 0.67945 0.3048)
			(end 0.67945 -0.305054)
			(stroke
				(width 0.1)
				(type default)
			)
			(layer "B.Fab")
		)
		(fp_line
			(start 0.67945 -0.305054)
			(end 0.12065 -0.305054)
			(stroke
				(width 0.1)
				(type default)
			)
			(layer "B.Fab")
		)
		(fp_line
			(start 0.12065 0.3048)
			(end 0.67945 0.3048)
			(stroke
				(width 0.1)
				(type default)
			)
			(layer "B.Fab")
		)
		(fp_line
			(start 0.12065 0.2794)
			(end 0.12065 0.3048)
			(stroke
				(width 0.1)
				(type default)
			)
			(layer "B.Fab")
		)
		(fp_line
			(start 0.12065 -0.2794)
			(end -0.12065 -0.2794)
			(stroke
				(width 0.1)
				(type default)
			)
			(layer "B.Fab")
		)
		(fp_line
			(start 0.12065 -0.305054)
			(end 0.12065 -0.2794)
			(stroke
				(width 0.1)
				(type default)
			)
			(layer "B.Fab")
		)
		(fp_line
			(start -0.120396 0.3048)
			(end -0.120396 0.2794)
			(stroke
				(width 0.1)
				(type default)
			)
			(layer "B.Fab")
		)
		(fp_line
			(start -0.120396 0.2794)
			(end 0.12065 0.2794)
			(stroke
				(width 0.1)
				(type default)
			)
			(layer "B.Fab")
		)
		(fp_line
			(start -0.12065 -0.2794)
			(end -0.12065 -0.3048)
			(stroke
				(width 0.1)
				(type default)
			)
			(layer "B.Fab")
		)
		(fp_line
			(start -0.12065 -0.3048)
			(end -0.67945 -0.3048)
			(stroke
				(width 0.1)
				(type default)
			)
			(layer "B.Fab")
		)
		(fp_line
			(start -0.67945 0.3048)
			(end -0.120396 0.3048)
			(stroke
				(width 0.1)
				(type default)
			)
			(layer "B.Fab")
		)
		(fp_line
			(start -0.67945 -0.3048)
			(end -0.67945 0.3048)
			(stroke
				(width 0.1)
				(type default)
			)
			(layer "B.Fab")
		)
		(pad "1" smd circle
			(at 0.40005 0)
			(size 0 0)
			(layers "B.Cu" "B.Mask" "B.Paste")
			(net "SPI_PEX1_SDIO2_R1")
		)
		(pad "2" smd circle
			(at -0.40005 0)
			(size 0 0)
			(layers "B.Cu" "B.Mask" "B.Paste")
			(net "GND")
		)
	)
	(footprint ""
		(layer "B.Cu")
		(at 299.95114 -305.399948 -90)
		(property "Reference" "C3323"
			(at 0 0 90)
			(layer "B.SilkS")
			(hide yes)
			(effects
				(font
					(size 1.27 1.27)
				)
				(justify mirror)
			)
		)
		(property "Value" ""
			(at 0 0 90)
			(layer "B.Fab")
			(effects
				(font
					(size 1.27 1.27)
				)
				(justify mirror)
			)
		)
		(duplicate_pad_numbers_are_jumpers no)
		(fp_line
			(start -0.299974 0.150114)
			(end 0.299974 0.150114)
			(stroke
				(width 0.1)
				(type default)
			)
			(layer "B.Fab")
		)
		(fp_line
			(start 0.299974 0.150114)
			(end 0.299974 -0.150114)
			(stroke
				(width 0.1)
				(type default)
			)
			(layer "B.Fab")
		)
		(fp_line
			(start -0.299974 -0.150114)
			(end -0.299974 0.150114)
			(stroke
				(width 0.1)
				(type default)
			)
			(layer "B.Fab")
		)
		(fp_line
			(start 0.299974 -0.150114)
			(end -0.299974 -0.150114)
			(stroke
				(width 0.1)
				(type default)
			)
			(layer "B.Fab")
		)
		(pad "1" smd rect
			(at 0.2667 0 90)
			(size 0.3048 0.381)
			(layers "B.Cu" "B.Mask" "B.Paste")
			(net "P1V25_SERDES_VDDPLL_PEX2")
		)
		(pad "2" smd rect
			(at -0.2667 0 90)
			(size 0.3048 0.381)
			(layers "B.Cu" "B.Mask" "B.Paste")
			(net "GND")
		)
	)
	(footprint ""
		(layer "B.Cu")
		(at 398.46504 -301.599854 -90)
		(property "Reference" "C1952"
			(at 0 0 90)
			(layer "B.SilkS")
			(hide yes)
			(effects
				(font
					(size 1.27 1.27)
				)
				(justify mirror)
			)
		)
		(property "Value" ""
			(at 0 0 90)
			(layer "B.Fab")
			(effects
				(font
					(size 1.27 1.27)
				)
				(justify mirror)
			)
		)
		(duplicate_pad_numbers_are_jumpers no)
		(fp_line
			(start -0.299974 0.150114)
			(end 0.299974 0.150114)
			(stroke
				(width 0.1)
				(type default)
			)
			(layer "B.Fab")
		)
		(fp_line
			(start 0.299974 0.150114)
			(end 0.299974 -0.150114)
			(stroke
				(width 0.1)
				(type default)
			)
			(layer "B.Fab")
		)
		(fp_line
			(start -0.299974 -0.150114)
			(end -0.299974 0.150114)
			(stroke
				(width 0.1)
				(type default)
			)
			(layer "B.Fab")
		)
		(fp_line
			(start 0.299974 -0.150114)
			(end -0.299974 -0.150114)
			(stroke
				(width 0.1)
				(type default)
			)
			(layer "B.Fab")
		)
		(pad "1" smd rect
			(at 0.2667 0 90)
			(size 0.3048 0.381)
			(layers "B.Cu" "B.Mask" "B.Paste")
			(net "P0V8_SERDES_VDDA_PEX3")
		)
		(pad "2" smd rect
			(at -0.2667 0 90)
			(size 0.3048 0.381)
			(layers "B.Cu" "B.Mask" "B.Paste")
			(net "GND")
		)
	)
	(footprint ""
		(layer "B.Cu")
		(at 186.203844 -98.552)
		(property "Reference" "R176"
			(at 0 0 0)
			(layer "B.SilkS")
			(hide yes)
			(effects
				(font
					(size 1.27 1.27)
				)
				(justify mirror)
			)
		)
		(property "Value" ""
			(at 0 0 0)
			(layer "B.Fab")
			(effects
				(font
					(size 1.27 1.27)
				)
				(justify mirror)
			)
		)
		(duplicate_pad_numbers_are_jumpers no)
		(fp_line
			(start -0.7874 -0.4064)
			(end -0.7874 0.4064)
			(stroke
				(width 0.1524)
				(type default)
			)
			(layer "B.SilkS")
		)
		(fp_line
			(start -0.7874 0.4064)
			(end 0.7874 0.4064)
			(stroke
				(width 0.1524)
				(type default)
			)
			(layer "B.SilkS")
		)
		(fp_line
			(start 0.7874 -0.4064)
			(end -0.7874 -0.4064)
			(stroke
				(width 0.1524)
				(type default)
			)
			(layer "B.SilkS")
		)
		(fp_line
			(start 0.7874 0.4064)
			(end 0.7874 -0.4064)
			(stroke
				(width 0.1524)
				(type default)
			)
			(layer "B.SilkS")
		)
		(fp_line
			(start -0.67945 -0.3048)
			(end -0.67945 0.3048)
			(stroke
				(width 0.1)
				(type default)
			)
			(layer "B.Fab")
		)
		(fp_line
			(start -0.67945 0.3048)
			(end -0.120396 0.3048)
			(stroke
				(width 0.1)
				(type default)
			)
			(layer "B.Fab")
		)
		(fp_line
			(start -0.12065 -0.3048)
			(end -0.67945 -0.3048)
			(stroke
				(width 0.1)
				(type default)
			)
			(layer "B.Fab")
		)
		(fp_line
			(start -0.12065 -0.2794)
			(end -0.12065 -0.3048)
			(stroke
				(width 0.1)
				(type default)
			)
			(layer "B.Fab")
		)
		(fp_line
			(start -0.120396 0.2794)
			(end 0.12065 0.2794)
			(stroke
				(width 0.1)
				(type default)
			)
			(layer "B.Fab")
		)
		(fp_line
			(start -0.120396 0.3048)
			(end -0.120396 0.2794)
			(stroke
				(width 0.1)
				(type default)
			)
			(layer "B.Fab")
		)
		(fp_line
			(start 0.12065 -0.305054)
			(end 0.12065 -0.2794)
			(stroke
				(width 0.1)
				(type default)
			)
			(layer "B.Fab")
		)
		(fp_line
			(start 0.12065 -0.2794)
			(end -0.12065 -0.2794)
			(stroke
				(width 0.1)
				(type default)
			)
			(layer "B.Fab")
		)
		(fp_line
			(start 0.12065 0.2794)
			(end 0.12065 0.3048)
			(stroke
				(width 0.1)
				(type default)
			)
			(layer "B.Fab")
		)
		(fp_line
			(start 0.12065 0.3048)
			(end 0.67945 0.3048)
			(stroke
				(width 0.1)
				(type default)
			)
			(layer "B.Fab")
		)
		(fp_line
			(start 0.67945 -0.305054)
			(end 0.12065 -0.305054)
			(stroke
				(width 0.1)
				(type default)
			)
			(layer "B.Fab")
		)
		(fp_line
			(start 0.67945 0.3048)
			(end 0.67945 -0.305054)
			(stroke
				(width 0.1)
				(type default)
			)
			(layer "B.Fab")
		)
		(pad "1" smd circle
			(at 0.40005 0 180)
			(size 0 0)
			(layers "B.Cu" "B.Mask" "B.Paste")
			(net "NIC3_MAIN_PWR_EN")
		)
		(pad "2" smd circle
			(at -0.40005 0 180)
			(size 0 0)
			(layers "B.Cu" "B.Mask" "B.Paste")
			(net "GND")
		)
	)
	(footprint ""
		(layer "B.Cu")
		(at 342.893396 -221.98711 90)
		(property "Reference" "C2032"
			(at 0 0 90)
			(layer "B.SilkS")
			(hide yes)
			(effects
				(font
					(size 1.27 1.27)
				)
				(justify mirror)
			)
		)
		(property "Value" ""
			(at 0 0 90)
			(layer "B.Fab")
			(effects
				(font
					(size 1.27 1.27)
				)
				(justify mirror)
			)
		)
		(duplicate_pad_numbers_are_jumpers no)
		(fp_line
			(start 0.69215 -0.2921)
			(end -0.69215 -0.2921)
			(stroke
				(width 0.1524)
				(type default)
			)
			(layer "B.SilkS")
		)
		(fp_line
			(start -0.69215 -0.2921)
			(end -0.69215 0.2921)
			(stroke
				(width 0.1524)
				(type default)
			)
			(layer "B.SilkS")
		)
		(fp_line
			(start 0.69215 0.2921)
			(end 0.69215 -0.2921)
			(stroke
				(width 0.1524)
				(type default)
			)
			(layer "B.SilkS")
		)
		(fp_line
			(start -0.69215 0.2921)
			(end 0.69215 0.2921)
			(stroke
				(width 0.1524)
				(type default)
			)
			(layer "B.SilkS")
		)
		(fp_line
			(start 0.51435 -0.2794)
			(end -0.51435 -0.2794)
			(stroke
				(width 0.1)
				(type default)
			)
			(layer "B.Fab")
		)
		(fp_line
			(start -0.51435 -0.2794)
			(end -0.51435 0.2794)
			(stroke
				(width 0.1)
				(type default)
			)
			(layer "B.Fab")
		)
		(fp_line
			(start 0.51435 0.2794)
			(end 0.51435 -0.2794)
			(stroke
				(width 0.1)
				(type default)
			)
			(layer "B.Fab")
		)
		(fp_line
			(start -0.51435 0.2794)
			(end 0.51435 0.2794)
			(stroke
				(width 0.1)
				(type default)
			)
			(layer "B.Fab")
		)
		(pad "1" smd circle
			(at 0.40005 0 270)
			(size 0 0)
			(layers "B.Cu" "B.Mask" "B.Paste")
			(net "P3V3_FPGA_VCCIO0")
		)
		(pad "2" smd circle
			(at -0.40005 0 270)
			(size 0 0)
			(layers "B.Cu" "B.Mask" "B.Paste")
			(net "GND")
		)
		(zone
			(layer "B.Cu")
			(hatch none 0.5)
			(connect_pads
				(clearance 0)
			)
			(min_thickness 0.25)
			(keepout
				(tracks not_allowed)
				(vias allowed)
				(pads allowed)
				(copperpour not_allowed)
				(footprints allowed)
			)
			(placement
				(enabled no)
				(sheetname "")
			)
			(fill
				(thermal_gap 0.5)
				(thermal_bridge_width 0.5)
				(island_removal_mode 0)
			)
			(polygon
				(pts
					(xy 342.981026 -222.17761) (xy 343.039192 -222.08617) (xy 343.039192 -221.88678) (xy 342.981026 -221.79661)
					(xy 342.805766 -221.79661) (xy 342.747346 -221.88678) (xy 342.747346 -222.08617) (xy 342.805512 -222.17761)
				)
			)
		)
	)
	(footprint ""
		(layer "B.Cu")
		(at 240.43767 -219.639134 180)
		(property "Reference" "C3619"
			(at 0 0 0)
			(layer "B.SilkS")
			(hide yes)
			(effects
				(font
					(size 1.27 1.27)
				)
				(justify mirror)
			)
		)
		(property "Value" ""
			(at 0 0 0)
			(layer "B.Fab")
			(effects
				(font
					(size 1.27 1.27)
				)
				(justify mirror)
			)
		)
		(duplicate_pad_numbers_are_jumpers no)
		(fp_line
			(start 0.69215 0.2921)
			(end 0.69215 -0.2921)
			(stroke
				(width 0.1524)
				(type default)
			)
			(layer "B.SilkS")
		)
		(fp_line
			(start 0.69215 -0.2921)
			(end -0.69215 -0.2921)
			(stroke
				(width 0.1524)
				(type default)
			)
			(layer "B.SilkS")
		)
		(fp_line
			(start -0.69215 0.2921)
			(end 0.69215 0.2921)
			(stroke
				(width 0.1524)
				(type default)
			)
			(layer "B.SilkS")
		)
		(fp_line
			(start -0.69215 -0.2921)
			(end -0.69215 0.2921)
			(stroke
				(width 0.1524)
				(type default)
			)
			(layer "B.SilkS")
		)
		(fp_line
			(start 0.51435 0.2794)
			(end 0.51435 -0.2794)
			(stroke
				(width 0.1)
				(type default)
			)
			(layer "B.Fab")
		)
		(fp_line
			(start 0.51435 -0.2794)
			(end -0.51435 -0.2794)
			(stroke
				(width 0.1)
				(type default)
			)
			(layer "B.Fab")
		)
		(fp_line
			(start -0.51435 0.2794)
			(end 0.51435 0.2794)
			(stroke
				(width 0.1)
				(type default)
			)
			(layer "B.Fab")
		)
		(fp_line
			(start -0.51435 -0.2794)
			(end -0.51435 0.2794)
			(stroke
				(width 0.1)
				(type default)
			)
			(layer "B.Fab")
		)
		(pad "1" smd circle
			(at 0.40005 0)
			(size 0 0)
			(layers "B.Cu" "B.Mask" "B.Paste")
			(net "BIC_ADCVREFN1")
		)
		(pad "2" smd circle
			(at -0.40005 0)
			(size 0 0)
			(layers "B.Cu" "B.Mask" "B.Paste")
			(net "GND")
		)
		(zone
			(layer "B.Cu")
			(hatch none 0.5)
			(connect_pads
				(clearance 0)
			)
			(min_thickness 0.25)
			(keepout
				(tracks not_allowed)
				(vias allowed)
				(pads allowed)
				(copperpour not_allowed)
				(footprints allowed)
			)
			(placement
				(enabled no)
				(sheetname "")
			)
			(fill
				(thermal_gap 0.5)
				(thermal_bridge_width 0.5)
				(island_removal_mode 0)
			)
			(polygon
				(pts
					(xy 240.24717 -219.726764) (xy 240.33861 -219.78493) (xy 240.538 -219.78493) (xy 240.62817 -219.726764)
					(xy 240.62817 -219.551504) (xy 240.538 -219.493084) (xy 240.33861 -219.493084) (xy 240.24717 -219.55125)
				)
			)
		)
	)
)
